(kicad_pcb
	(version 20241229)
	(generator "pcbnew")
	(generator_version "9.0")
	(general
		(thickness 1.552)
		(legacy_teardrops no)
	)
	(paper "A4")
	(title_block
		(date "2023-07-25")
		(rev "1.1.4")
		(comment 9 "footprints 67-70 of 379")
	)
	(layers
		(0 "F.Cu" signal)
		(4 "In1.Cu" signal)
		(6 "In2.Cu" signal)
		(8 "In3.Cu" signal)
		(10 "In4.Cu" signal)
		(12 "In5.Cu" signal)
		(14 "In6.Cu" signal)
		(2 "B.Cu" signal)
		(9 "F.Adhes" user "F.Adhesive")
		(11 "B.Adhes" user "B.Adhesive")
		(13 "F.Paste" user)
		(15 "B.Paste" user)
		(5 "F.SilkS" user "F.Silkscreen")
		(7 "B.SilkS" user "B.Silkscreen")
		(1 "F.Mask" user)
		(3 "B.Mask" user)
		(17 "Dwgs.User" user "User.Drawings")
		(19 "Cmts.User" user "User.Comments")
		(21 "Eco1.User" user "User.Eco1")
		(23 "Eco2.User" user "User.Eco2")
		(25 "Edge.Cuts" user)
		(27 "Margin" user)
		(31 "F.CrtYd" user "F.Courtyard")
		(29 "B.CrtYd" user "B.Courtyard")
		(35 "F.Fab" user)
		(33 "B.Fab" user)
	)
	(footprint "antmicro-footprints:C_0402_1005Metric"
		(layer "F.Cu")
		(at 115.8 88.8 90)
		(descr "Capacitor SMD 0402")
		(tags "capacitor SMD 0402")
		(property "Reference" "C79"
			(at -1.14 1.43 90)
			(layer "F.SilkS")
			(effects
				(font
					(size 0.65 0.65)
					(thickness 0.15)
				)
				(justify left bottom)
			)
		)
		(property "Value" "C_100n_0402"
			(at 0 1.4 90)
			(layer "F.Fab")
			(hide yes)
			(effects
				(font
					(size 0.7 0.7)
					(thickness 0.15)
				)
				(justify left bottom)
			)
		)
		(property "Datasheet" "https://www.murata.com/products/productdetail?partno=GRM155R61H104KE14%23"
			(at 0 0 90)
			(layer "F.Fab")
			(hide yes)
			(effects
				(font
					(size 1.27 1.27)
					(thickness 0.15)
				)
			)
		)
		(property "Description" "SMD Multilayer Ceramic Capacitor, 0.1 µF, 50 V, 0402 [1005 Metric], ± 10%, X5R, GRM Series"
			(at 0 0 90)
			(layer "F.Fab")
			(hide yes)
			(effects
				(font
					(size 1.27 1.27)
					(thickness 0.15)
				)
			)
		)
		(property "Author" "Antmicro"
			(at 204.6 -27 0)
			(layer "F.Fab")
			(hide yes)
			(effects
				(font
					(size 1 1)
					(thickness 0.15)
				)
			)
		)
		(property "Dielectric" "X5R"
			(at 204.6 -27 0)
			(layer "F.Fab")
			(hide yes)
			(effects
				(font
					(size 1 1)
					(thickness 0.15)
				)
			)
		)
		(property "License" "Apache-2.0"
			(at 204.6 -27 0)
			(layer "F.Fab")
			(hide yes)
			(effects
				(font
					(size 1 1)
					(thickness 0.15)
				)
			)
		)
		(property "MPN" "GRM155R61H104KE14D"
			(at 204.6 -27 0)
			(layer "F.Fab")
			(hide yes)
			(effects
				(font
					(size 1 1)
					(thickness 0.15)
				)
			)
		)
		(property "Manufacturer" "Murata"
			(at 204.6 -27 0)
			(layer "F.Fab")
			(hide yes)
			(effects
				(font
					(size 1 1)
					(thickness 0.15)
				)
			)
		)
		(property "Val" "100n"
			(at 204.6 -27 0)
			(layer "F.Fab")
			(hide yes)
			(effects
				(font
					(size 1 1)
					(thickness 0.15)
				)
			)
		)
		(property "Voltage" "50V"
			(at 204.6 -27 0)
			(layer "F.Fab")
			(hide yes)
			(effects
				(font
					(size 1 1)
					(thickness 0.15)
				)
			)
		)
		(sheetname "/FPGA/")
		(sheetfile "fpga.kicad_sch")
		(attr smd)
		(fp_rect
			(start -0.925 -0.47)
			(end 0.925 0.47)
			(stroke
				(width 0.05)
				(type default)
			)
			(fill no)
			(layer "F.CrtYd")
		)
		(fp_line
			(start 0.504 -0.25)
			(end 0.504 0.248)
			(stroke
				(width 0.15)
				(type solid)
			)
			(layer "F.Fab")
		)
		(fp_line
			(start -0.494 -0.25)
			(end 0.504 -0.25)
			(stroke
				(width 0.15)
				(type solid)
			)
			(layer "F.Fab")
		)
		(fp_line
			(start 0.504 0.248)
			(end -0.494 0.248)
			(stroke
				(width 0.15)
				(type solid)
			)
			(layer "F.Fab")
		)
		(fp_line
			(start -0.494 0.248)
			(end -0.494 -0.25)
			(stroke
				(width 0.15)
				(type solid)
			)
			(layer "F.Fab")
		)
		(fp_text user "${REFERENCE}"
			(at -0.939 4.599 90)
			(layer "F.Fab")
			(effects
				(font
					(size 0.7 0.7)
					(thickness 0.15)
				)
				(justify left bottom)
			)
		)
		(fp_text user "License: Apache-2.0"
			(at -0.939 5.799 90)
			(layer "F.Fab")
			(effects
				(font
					(size 0.7 0.7)
					(thickness 0.15)
				)
				(justify left bottom)
			)
		)
		(fp_text user "Author: Antmicro"
			(at -0.939 3.399 90)
			(layer "F.Fab")
			(effects
				(font
					(size 0.7 0.7)
					(thickness 0.15)
				)
				(justify left bottom)
			)
		)
		(pad "1" smd roundrect
			(at -0.48 0 90)
			(size 0.59 0.64)
			(layers "F.Cu" "F.Mask" "F.Paste")
			(roundrect_rratio 0.25)
			(net 1 "GND")
			(pintype "passive")
		)
		(pad "2" smd roundrect
			(at 0.48 0 90)
			(size 0.59 0.64)
			(layers "F.Cu" "F.Mask" "F.Paste")
			(roundrect_rratio 0.25)
			(net 2 "+3V3")
			(pintype "passive")
		)
	)
	(footprint "antmicro-footprints:R_0402_1005Metric"
		(layer "F.Cu")
		(at 110.79 101.4)
		(descr "Resistor SMD 0402")
		(tags "resistor SMD 0402")
		(property "Reference" "R80"
			(at 0.94 0.44 0)
			(layer "F.SilkS")
			(effects
				(font
					(size 0.65 0.65)
					(thickness 0.15)
				)
				(justify left bottom)
			)
		)
		(property "Value" "R_0R_0402"
			(at 0 1.4 0)
			(layer "F.Fab")
			(hide yes)
			(effects
				(font
					(size 0.7 0.7)
					(thickness 0.15)
				)
				(justify left bottom)
			)
		)
		(property "Datasheet" "https://industrial.panasonic.com/cdbs/www-data/pdf/RDA0000/AOA0000C301.pdf"
			(at 0 0 0)
			(layer "F.Fab")
			(hide yes)
			(effects
				(font
					(size 1.27 1.27)
					(thickness 0.15)
				)
			)
		)
		(property "Description" "SMD Chip Resistor, Jumper, 0 ohm, 100 mW, 0402 [1005 Metric], Thick Film, General Purpose"
			(at 0 0 0)
			(layer "F.Fab")
			(hide yes)
			(effects
				(font
					(size 1.27 1.27)
					(thickness 0.15)
				)
			)
		)
		(property "Author" "Antmicro"
			(at 0 0 0)
			(layer "F.Fab")
			(hide yes)
			(effects
				(font
					(size 1 1)
					(thickness 0.15)
				)
			)
		)
		(property "Current" "1A"
			(at 0 0 0)
			(layer "F.Fab")
			(hide yes)
			(effects
				(font
					(size 1 1)
					(thickness 0.15)
				)
			)
		)
		(property "License" "Apache-2.0"
			(at 0 0 0)
			(layer "F.Fab")
			(hide yes)
			(effects
				(font
					(size 1 1)
					(thickness 0.15)
				)
			)
		)
		(property "MPN" "ERJ2GE0R00X"
			(at 0 0 0)
			(layer "F.Fab")
			(hide yes)
			(effects
				(font
					(size 1 1)
					(thickness 0.15)
				)
			)
		)
		(property "Manufacturer" "Panasonic"
			(at 0 0 0)
			(layer "F.Fab")
			(hide yes)
			(effects
				(font
					(size 1 1)
					(thickness 0.15)
				)
			)
		)
		(property "Tolerance" "~"
			(at 0 0 0)
			(layer "F.Fab")
			(hide yes)
			(effects
				(font
					(size 1 1)
					(thickness 0.15)
				)
			)
		)
		(property "Val" "0R"
			(at 0 0 0)
			(layer "F.Fab")
			(hide yes)
			(effects
				(font
					(size 1 1)
					(thickness 0.15)
				)
			)
		)
		(sheetname "/FPGA/")
		(sheetfile "fpga.kicad_sch")
		(attr smd)
		(fp_rect
			(start -0.925 -0.47)
			(end 0.925 0.47)
			(stroke
				(width 0.05)
				(type default)
			)
			(fill no)
			(layer "F.CrtYd")
		)
		(fp_rect
			(start -0.5 -0.25)
			(end 0.5 0.25)
			(stroke
				(width 0.15)
				(type solid)
			)
			(fill no)
			(layer "F.Fab")
		)
		(fp_text user "Author: Antmicro"
			(at -0.95 4.169 0)
			(layer "F.Fab")
			(effects
				(font
					(size 0.7 0.7)
					(thickness 0.15)
				)
				(justify left bottom)
			)
		)
		(fp_text user "License: Apache-2.0"
			(at -0.95 5.169 0)
			(layer "F.Fab")
			(effects
				(font
					(size 0.7 0.7)
					(thickness 0.15)
				)
				(justify left bottom)
			)
		)
		(fp_text user "${REFERENCE}"
			(at -0.95 3.168 0)
			(layer "F.Fab")
			(effects
				(font
					(size 0.7 0.7)
					(thickness 0.15)
				)
				(justify left bottom)
			)
		)
		(pad "1" smd roundrect
			(at -0.48 0)
			(size 0.59 0.64)
			(layers "F.Cu" "F.Mask" "F.Paste")
			(roundrect_rratio 0.25)
			(net 316 "Net-(U17-A1)")
			(pintype "passive")
		)
		(pad "2" smd roundrect
			(at 0.48 0)
			(size 0.59 0.64)
			(layers "F.Cu" "F.Mask" "F.Paste")
			(roundrect_rratio 0.25)
			(net 1 "GND")
			(pintype "passive")
		)
	)
	(footprint "antmicro-footprints:TP_SMD_0.75mm"
		(layer "F.Cu")
		(at 139.4 55.93)
		(property "Reference" "TP1"
			(at -3.595 0.44 0)
			(layer "F.SilkS")
			(effects
				(font
					(size 0.65 0.65)
					(thickness 0.15)
				)
				(justify left bottom)
			)
		)
		(property "Value" "TP_0.75mm_SMD"
			(at 0 1.2 0)
			(layer "F.Fab")
			(hide yes)
			(effects
				(font
					(size 0.7 0.7)
					(thickness 0.15)
				)
				(justify left bottom)
			)
		)
		(property "Description" "SMT test point"
			(at 0 0 0)
			(layer "F.Fab")
			(hide yes)
			(effects
				(font
					(size 1.27 1.27)
					(thickness 0.15)
				)
			)
		)
		(property "Author" "Antmicro"
			(at 0 0 0)
			(layer "F.Fab")
			(hide yes)
			(effects
				(font
					(size 1 1)
					(thickness 0.15)
				)
			)
		)
		(property "License" "Apache-2.0"
			(at 0 0 0)
			(layer "F.Fab")
			(hide yes)
			(effects
				(font
					(size 1 1)
					(thickness 0.15)
				)
			)
		)
		(property "MPN" ""
			(at 0 0 0)
			(layer "F.Fab")
			(hide yes)
			(effects
				(font
					(size 1 1)
					(thickness 0.15)
				)
			)
		)
		(property "Manufacturer" ""
			(at 0 0 0)
			(layer "F.Fab")
			(hide yes)
			(effects
				(font
					(size 1 1)
					(thickness 0.15)
				)
			)
		)
		(sheetname "/Power Supply/")
		(sheetfile "supply.kicad_sch")
		(attr exclude_from_pos_files)
		(fp_circle
			(center 0 0)
			(end 0.475 0)
			(stroke
				(width 0.05)
				(type default)
			)
			(fill no)
			(layer "F.CrtYd")
		)
		(fp_text user "License: Apache-2.0"
			(at -0.4 5.101 0)
			(layer "F.Fab")
			(effects
				(font
					(size 0.7 0.7)
					(thickness 0.15)
				)
				(justify left bottom)
			)
		)
		(fp_text user "${REFERENCE}"
			(at -0.4 2.7 0)
			(layer "F.Fab")
			(effects
				(font
					(size 0.7 0.7)
					(thickness 0.15)
				)
				(justify left bottom)
			)
		)
		(fp_text user "Author: Antmicro"
			(at -0.4 3.901 0)
			(layer "F.Fab")
			(effects
				(font
					(size 0.7 0.7)
					(thickness 0.15)
				)
				(justify left bottom)
			)
		)
		(pad "1" smd circle
			(at 0 0)
			(size 0.75 0.75)
			(layers "F.Cu" "F.Mask")
			(net 1 "GND")
			(pinfunction "1")
			(pintype "passive")
		)
	)
	(footprint "antmicro-footprints:C_0603_1608Metric"
		(layer "F.Cu")
		(at 167.03 88.75 -90)
		(descr "Capacitor SMD 0603")
		(tags "capacitor 0603")
		(property "Reference" "C111"
			(at -1.21 -1.5 90)
			(layer "F.SilkS")
			(effects
				(font
					(size 0.65 0.65)
					(thickness 0.15)
				)
				(justify right bottom)
			)
		)
		(property "Value" "C_1u_0603"
			(at 0 1.6 90)
			(layer "F.Fab")
			(hide yes)
			(effects
				(font
					(size 0.7 0.7)
					(thickness 0.15)
				)
				(justify right bottom)
			)
		)
		(property "Datasheet" "https://spicat.kyocera-avx.com/product/mlcc/chartview/0603YD105KAT2A/"
			(at 0 0 270)
			(layer "F.Fab")
			(hide yes)
			(effects
				(font
					(size 1.27 1.27)
					(thickness 0.15)
				)
			)
		)
		(property "Description" "SMD Multilayer Ceramic Capacitor, 1 µF, 16 V, 0603 [1608 Metric], ± 10%, X5R, AVX 0603 MLCC"
			(at 0 0 270)
			(layer "F.Fab")
			(hide yes)
			(effects
				(font
					(size 1.27 1.27)
					(thickness 0.15)
				)
			)
		)
		(property "Author" "Antmicro"
			(at 78.28 255.78 0)
			(layer "F.Fab")
			(hide yes)
			(effects
				(font
					(size 1 1)
					(thickness 0.15)
				)
			)
		)
		(property "Dielectric" ""
			(at 78.28 255.78 0)
			(layer "F.Fab")
			(hide yes)
			(effects
				(font
					(size 1 1)
					(thickness 0.15)
				)
			)
		)
		(property "License" "Apache-2.0"
			(at 78.28 255.78 0)
			(layer "F.Fab")
			(hide yes)
			(effects
				(font
					(size 1 1)
					(thickness 0.15)
				)
			)
		)
		(property "MPN" "0603YD105KAT2A"
			(at 78.28 255.78 0)
			(layer "F.Fab")
			(hide yes)
			(effects
				(font
					(size 1 1)
					(thickness 0.15)
				)
			)
		)
		(property "Manufacturer" "KYOCERA AVX"
			(at 78.28 255.78 0)
			(layer "F.Fab")
			(hide yes)
			(effects
				(font
					(size 1 1)
					(thickness 0.15)
				)
			)
		)
		(property "Val" "1u"
			(at 78.28 255.78 0)
			(layer "F.Fab")
			(hide yes)
			(effects
				(font
					(size 1 1)
					(thickness 0.15)
				)
			)
		)
		(property "Voltage" ""
			(at 78.28 255.78 0)
			(layer "F.Fab")
			(hide yes)
			(effects
				(font
					(size 1 1)
					(thickness 0.15)
				)
			)
		)
		(sheetname "/Peripherals/")
		(sheetfile "peripherals.kicad_sch")
		(attr smd)
		(fp_line
			(start -0.15 0.4)
			(end 0.15 0.4)
			(stroke
				(width 0.15)
				(type solid)
			)
			(layer "F.SilkS")
		)
		(fp_line
			(start -0.15 -0.4)
			(end 0.15 -0.4)
			(stroke
				(width 0.15)
				(type solid)
			)
			(layer "F.SilkS")
		)
		(fp_rect
			(start -1.25 -0.65)
			(end 1.25 0.65)
			(stroke
				(width 0.05)
				(type solid)
			)
			(fill no)
			(layer "F.CrtYd")
		)
		(fp_rect
			(start -0.8 -0.4)
			(end 0.8 0.4)
			(stroke
				(width 0.15)
				(type solid)
			)
			(fill no)
			(layer "F.Fab")
		)
		(fp_text user "Author: Antmicro"
			(at -1.682 4.894 270)
			(layer "F.Fab")
			(effects
				(font
					(size 0.7 0.7)
					(thickness 0.15)
				)
				(justify left bottom)
			)
		)
		(fp_text user "${REFERENCE}"
			(at -1.682 3.895 270)
			(layer "F.Fab")
			(effects
				(font
					(size 0.7 0.7)
					(thickness 0.15)
				)
				(justify left bottom)
			)
		)
		(fp_text user "License: Apache-2.0"
			(at -1.682 5.895 270)
			(layer "F.Fab")
			(effects
				(font
					(size 0.7 0.7)
					(thickness 0.15)
				)
				(justify left bottom)
			)
		)
		(pad "1" smd roundrect
			(at -0.7 0 270)
			(size 0.8 1)
			(layers "F.Cu" "F.Mask" "F.Paste")
			(roundrect_rratio 0.2)
			(net 1 "GND")
			(pintype "passive")
		)
		(pad "2" smd roundrect
			(at 0.7 0 270)
			(size 0.8 1)
			(layers "F.Cu" "F.Mask" "F.Paste")
			(roundrect_rratio 0.2)
			(net 17 "/Peripherals/FFC1_3V3")
			(pintype "passive")
		)
	)
)
